(kicad_pcb
	(version 20260206)
	(generator "pcbnew")
	(generator_version "10.0")
	(general
		(thickness 1.6)
		(legacy_teardrops no)
	)
	(paper "A4")
	(title_block
		(title "04192023_DAF0TMB3IC0_F0TG_MB_C_brd_V02_OCP.brd")
		(comment 1 "Grand Teton / footprints 828-833 of 8354")
	)
	(layers
		(0 "F.Cu" signal "TOP")
		(4 "In1.Cu" signal "GND")
		(6 "In2.Cu" signal "IN1")
		(8 "In3.Cu" signal "GND1")
		(10 "In4.Cu" signal "IN2")
		(12 "In5.Cu" signal "GND2")
		(14 "In6.Cu" signal "IN3")
		(16 "In7.Cu" signal "GND3")
		(18 "In8.Cu" signal "VCC")
		(20 "In9.Cu" signal "VCC1")
		(22 "In10.Cu" signal "GND4")
		(24 "In11.Cu" signal "IN4")
		(26 "In12.Cu" signal "GND5")
		(28 "In13.Cu" signal "IN5")
		(30 "In14.Cu" signal "GND6")
		(32 "In15.Cu" signal "IN6")
		(34 "In16.Cu" signal "GND7")
		(2 "B.Cu" signal "BOTTOM")
		(9 "F.Adhes" user "F.Adhesive")
		(11 "B.Adhes" user "B.Adhesive")
		(13 "F.Paste" user "Package Geometry/Pastemask Top")
		(15 "B.Paste" user "Package Geometry/Pastemask Bottom")
		(5 "F.SilkS" user "Ref Des/Silkscreen Top")
		(7 "B.SilkS" user "Ref Des/Silkscreen Bottom")
		(1 "F.Mask" user "Board Geometry/Soldermask Top")
		(3 "B.Mask" user "Board Geometry/Soldermask Bottom")
		(17 "Dwgs.User" user "User.Drawings")
		(19 "Cmts.User" user "User.Comments")
		(21 "Eco1.User" user "User.Eco1")
		(23 "Eco2.User" user "User.Eco2")
		(25 "Edge.Cuts" user "Board Geometry/Outline")
		(27 "Margin" user)
		(31 "F.CrtYd" user "Package Geometry/Place Bound Top")
		(29 "B.CrtYd" user "Package Geometry/Place Bound Bottom")
		(35 "F.Fab" user "Ref Des/Assembly Top")
		(33 "B.Fab" user "Ref Des/Assembly Bottom")
	)
	(footprint ""
		(layer "F.Cu")
		(at 217.889582 -69.397118)
		(property "Reference" "PC2212"
			(at 0 0 0)
			(layer "F.SilkS")
			(hide yes)
			(effects
				(font
					(size 1.27 1.27)
				)
			)
		)
		(property "Value" ""
			(at 0 0 0)
			(layer "F.Fab")
			(effects
				(font
					(size 1.27 1.27)
				)
			)
		)
		(duplicate_pad_numbers_are_jumpers no)
		(fp_line
			(start -0.7874 -0.4064)
			(end 0.7874 -0.4064)
			(stroke
				(width 0.1524)
				(type default)
			)
			(layer "F.SilkS")
		)
		(fp_line
			(start -0.7874 0.4064)
			(end -0.7874 -0.4064)
			(stroke
				(width 0.1524)
				(type default)
			)
			(layer "F.SilkS")
		)
		(fp_line
			(start 0.7874 -0.4064)
			(end 0.7874 0.4064)
			(stroke
				(width 0.1524)
				(type default)
			)
			(layer "F.SilkS")
		)
		(fp_line
			(start 0.7874 0.4064)
			(end -0.7874 0.4064)
			(stroke
				(width 0.1524)
				(type default)
			)
			(layer "F.SilkS")
		)
		(fp_line
			(start -0.67945 -0.305054)
			(end -0.12065 -0.305054)
			(stroke
				(width 0.1)
				(type default)
			)
			(layer "F.Fab")
		)
		(fp_line
			(start -0.67945 0.3048)
			(end -0.67945 -0.305054)
			(stroke
				(width 0.1)
				(type default)
			)
			(layer "F.Fab")
		)
		(fp_line
			(start -0.12065 -0.305054)
			(end -0.12065 -0.2794)
			(stroke
				(width 0.1)
				(type default)
			)
			(layer "F.Fab")
		)
		(fp_line
			(start -0.12065 -0.2794)
			(end 0.12065 -0.2794)
			(stroke
				(width 0.1)
				(type default)
			)
			(layer "F.Fab")
		)
		(fp_line
			(start -0.12065 0.2794)
			(end -0.12065 0.3048)
			(stroke
				(width 0.1)
				(type default)
			)
			(layer "F.Fab")
		)
		(fp_line
			(start -0.12065 0.3048)
			(end -0.67945 0.3048)
			(stroke
				(width 0.1)
				(type default)
			)
			(layer "F.Fab")
		)
		(fp_line
			(start 0.120396 0.2794)
			(end -0.12065 0.2794)
			(stroke
				(width 0.1)
				(type default)
			)
			(layer "F.Fab")
		)
		(fp_line
			(start 0.120396 0.3048)
			(end 0.120396 0.2794)
			(stroke
				(width 0.1)
				(type default)
			)
			(layer "F.Fab")
		)
		(fp_line
			(start 0.12065 -0.3048)
			(end 0.67945 -0.3048)
			(stroke
				(width 0.1)
				(type default)
			)
			(layer "F.Fab")
		)
		(fp_line
			(start 0.12065 -0.2794)
			(end 0.12065 -0.3048)
			(stroke
				(width 0.1)
				(type default)
			)
			(layer "F.Fab")
		)
		(fp_line
			(start 0.67945 -0.3048)
			(end 0.67945 0.3048)
			(stroke
				(width 0.1)
				(type default)
			)
			(layer "F.Fab")
		)
		(fp_line
			(start 0.67945 0.3048)
			(end 0.120396 0.3048)
			(stroke
				(width 0.1)
				(type default)
			)
			(layer "F.Fab")
		)
		(pad "1" smd circle
			(at -0.40005 0)
			(size 0 0)
			(layers "F.Cu" "F.Mask" "F.Paste")
			(net "GND")
		)
		(pad "2" smd circle
			(at 0.40005 0)
			(size 0 0)
			(layers "F.Cu" "F.Mask" "F.Paste")
			(net "P3V3_E1S_REG_0")
		)
	)
	(footprint ""
		(layer "F.Cu")
		(at 259.834126 -100.016056 180)
		(property "Reference" "R1636"
			(at 0 0 180)
			(layer "F.SilkS")
			(hide yes)
			(effects
				(font
					(size 1.27 1.27)
				)
			)
		)
		(property "Value" ""
			(at 0 0 180)
			(layer "F.Fab")
			(effects
				(font
					(size 1.27 1.27)
				)
			)
		)
		(duplicate_pad_numbers_are_jumpers no)
		(fp_line
			(start 0.7874 0.4064)
			(end -0.7874 0.4064)
			(stroke
				(width 0.1524)
				(type default)
			)
			(layer "F.SilkS")
		)
		(fp_line
			(start 0.7874 -0.4064)
			(end 0.7874 0.4064)
			(stroke
				(width 0.1524)
				(type default)
			)
			(layer "F.SilkS")
		)
		(fp_line
			(start -0.7874 0.4064)
			(end -0.7874 -0.4064)
			(stroke
				(width 0.1524)
				(type default)
			)
			(layer "F.SilkS")
		)
		(fp_line
			(start -0.7874 -0.4064)
			(end 0.7874 -0.4064)
			(stroke
				(width 0.1524)
				(type default)
			)
			(layer "F.SilkS")
		)
		(fp_line
			(start 0.67945 0.3048)
			(end 0.120396 0.3048)
			(stroke
				(width 0.1)
				(type default)
			)
			(layer "F.Fab")
		)
		(fp_line
			(start 0.67945 -0.3048)
			(end 0.67945 0.3048)
			(stroke
				(width 0.1)
				(type default)
			)
			(layer "F.Fab")
		)
		(fp_line
			(start 0.12065 -0.2794)
			(end 0.12065 -0.3048)
			(stroke
				(width 0.1)
				(type default)
			)
			(layer "F.Fab")
		)
		(fp_line
			(start 0.12065 -0.3048)
			(end 0.67945 -0.3048)
			(stroke
				(width 0.1)
				(type default)
			)
			(layer "F.Fab")
		)
		(fp_line
			(start 0.120396 0.3048)
			(end 0.120396 0.2794)
			(stroke
				(width 0.1)
				(type default)
			)
			(layer "F.Fab")
		)
		(fp_line
			(start 0.120396 0.2794)
			(end -0.12065 0.2794)
			(stroke
				(width 0.1)
				(type default)
			)
			(layer "F.Fab")
		)
		(fp_line
			(start -0.12065 0.3048)
			(end -0.67945 0.3048)
			(stroke
				(width 0.1)
				(type default)
			)
			(layer "F.Fab")
		)
		(fp_line
			(start -0.12065 0.2794)
			(end -0.12065 0.3048)
			(stroke
				(width 0.1)
				(type default)
			)
			(layer "F.Fab")
		)
		(fp_line
			(start -0.12065 -0.2794)
			(end 0.12065 -0.2794)
			(stroke
				(width 0.1)
				(type default)
			)
			(layer "F.Fab")
		)
		(fp_line
			(start -0.12065 -0.305054)
			(end -0.12065 -0.2794)
			(stroke
				(width 0.1)
				(type default)
			)
			(layer "F.Fab")
		)
		(fp_line
			(start -0.67945 0.3048)
			(end -0.67945 -0.305054)
			(stroke
				(width 0.1)
				(type default)
			)
			(layer "F.Fab")
		)
		(fp_line
			(start -0.67945 -0.305054)
			(end -0.12065 -0.305054)
			(stroke
				(width 0.1)
				(type default)
			)
			(layer "F.Fab")
		)
		(pad "1" smd circle
			(at -0.40005 0 180)
			(size 0 0)
			(layers "F.Cu" "F.Mask" "F.Paste")
			(net "JTAG_DBREQ_R_N")
		)
		(pad "2" smd circle
			(at 0.40005 0 180)
			(size 0 0)
			(layers "F.Cu" "F.Mask" "F.Paste")
			(net "JTAG_DBREQ_N")
		)
	)
	(footprint ""
		(layer "F.Cu")
		(at 357.20401 -418.329618 180)
		(property "Reference" "R4155"
			(at 0 0 180)
			(layer "F.SilkS")
			(hide yes)
			(effects
				(font
					(size 1.27 1.27)
				)
			)
		)
		(property "Value" ""
			(at 0 0 180)
			(layer "F.Fab")
			(effects
				(font
					(size 1.27 1.27)
				)
			)
		)
		(duplicate_pad_numbers_are_jumpers no)
		(fp_line
			(start 0.7874 0.4064)
			(end -0.7874 0.4064)
			(stroke
				(width 0.1524)
				(type default)
			)
			(layer "F.SilkS")
		)
		(fp_line
			(start 0.7874 -0.4064)
			(end 0.7874 0.4064)
			(stroke
				(width 0.1524)
				(type default)
			)
			(layer "F.SilkS")
		)
		(fp_line
			(start -0.7874 0.4064)
			(end -0.7874 -0.4064)
			(stroke
				(width 0.1524)
				(type default)
			)
			(layer "F.SilkS")
		)
		(fp_line
			(start -0.7874 -0.4064)
			(end 0.7874 -0.4064)
			(stroke
				(width 0.1524)
				(type default)
			)
			(layer "F.SilkS")
		)
		(fp_line
			(start 0.67945 0.3048)
			(end 0.120396 0.3048)
			(stroke
				(width 0.1)
				(type default)
			)
			(layer "F.Fab")
		)
		(fp_line
			(start 0.67945 -0.3048)
			(end 0.67945 0.3048)
			(stroke
				(width 0.1)
				(type default)
			)
			(layer "F.Fab")
		)
		(fp_line
			(start 0.12065 -0.2794)
			(end 0.12065 -0.3048)
			(stroke
				(width 0.1)
				(type default)
			)
			(layer "F.Fab")
		)
		(fp_line
			(start 0.12065 -0.3048)
			(end 0.67945 -0.3048)
			(stroke
				(width 0.1)
				(type default)
			)
			(layer "F.Fab")
		)
		(fp_line
			(start 0.120396 0.3048)
			(end 0.120396 0.2794)
			(stroke
				(width 0.1)
				(type default)
			)
			(layer "F.Fab")
		)
		(fp_line
			(start 0.120396 0.2794)
			(end -0.12065 0.2794)
			(stroke
				(width 0.1)
				(type default)
			)
			(layer "F.Fab")
		)
		(fp_line
			(start -0.12065 0.3048)
			(end -0.67945 0.3048)
			(stroke
				(width 0.1)
				(type default)
			)
			(layer "F.Fab")
		)
		(fp_line
			(start -0.12065 0.2794)
			(end -0.12065 0.3048)
			(stroke
				(width 0.1)
				(type default)
			)
			(layer "F.Fab")
		)
		(fp_line
			(start -0.12065 -0.2794)
			(end 0.12065 -0.2794)
			(stroke
				(width 0.1)
				(type default)
			)
			(layer "F.Fab")
		)
		(fp_line
			(start -0.12065 -0.305054)
			(end -0.12065 -0.2794)
			(stroke
				(width 0.1)
				(type default)
			)
			(layer "F.Fab")
		)
		(fp_line
			(start -0.67945 0.3048)
			(end -0.67945 -0.305054)
			(stroke
				(width 0.1)
				(type default)
			)
			(layer "F.Fab")
		)
		(fp_line
			(start -0.67945 -0.305054)
			(end -0.12065 -0.305054)
			(stroke
				(width 0.1)
				(type default)
			)
			(layer "F.Fab")
		)
		(pad "1" smd circle
			(at -0.40005 0 180)
			(size 0 0)
			(layers "F.Cu" "F.Mask" "F.Paste")
			(net "P3V3_AUX")
		)
		(pad "2" smd circle
			(at 0.40005 0 180)
			(size 0 0)
			(layers "F.Cu" "F.Mask" "F.Paste")
			(net "PRSNT_CABLE_GPU_A1")
		)
	)
	(footprint ""
		(layer "F.Cu")
		(at 304.301398 -430.2379 180)
		(property "Reference" "R4131"
			(at 0 0 180)
			(layer "F.SilkS")
			(hide yes)
			(effects
				(font
					(size 1.27 1.27)
				)
			)
		)
		(property "Value" ""
			(at 0 0 180)
			(layer "F.Fab")
			(effects
				(font
					(size 1.27 1.27)
				)
			)
		)
		(duplicate_pad_numbers_are_jumpers no)
		(fp_line
			(start 0.7874 0.4064)
			(end -0.7874 0.4064)
			(stroke
				(width 0.1524)
				(type default)
			)
			(layer "F.SilkS")
		)
		(fp_line
			(start 0.7874 -0.4064)
			(end 0.7874 0.4064)
			(stroke
				(width 0.1524)
				(type default)
			)
			(layer "F.SilkS")
		)
		(fp_line
			(start -0.7874 0.4064)
			(end -0.7874 -0.4064)
			(stroke
				(width 0.1524)
				(type default)
			)
			(layer "F.SilkS")
		)
		(fp_line
			(start -0.7874 -0.4064)
			(end 0.7874 -0.4064)
			(stroke
				(width 0.1524)
				(type default)
			)
			(layer "F.SilkS")
		)
		(fp_line
			(start 0.67945 0.3048)
			(end 0.120396 0.3048)
			(stroke
				(width 0.1)
				(type default)
			)
			(layer "F.Fab")
		)
		(fp_line
			(start 0.67945 -0.3048)
			(end 0.67945 0.3048)
			(stroke
				(width 0.1)
				(type default)
			)
			(layer "F.Fab")
		)
		(fp_line
			(start 0.12065 -0.2794)
			(end 0.12065 -0.3048)
			(stroke
				(width 0.1)
				(type default)
			)
			(layer "F.Fab")
		)
		(fp_line
			(start 0.12065 -0.3048)
			(end 0.67945 -0.3048)
			(stroke
				(width 0.1)
				(type default)
			)
			(layer "F.Fab")
		)
		(fp_line
			(start 0.120396 0.3048)
			(end 0.120396 0.2794)
			(stroke
				(width 0.1)
				(type default)
			)
			(layer "F.Fab")
		)
		(fp_line
			(start 0.120396 0.2794)
			(end -0.12065 0.2794)
			(stroke
				(width 0.1)
				(type default)
			)
			(layer "F.Fab")
		)
		(fp_line
			(start -0.12065 0.3048)
			(end -0.67945 0.3048)
			(stroke
				(width 0.1)
				(type default)
			)
			(layer "F.Fab")
		)
		(fp_line
			(start -0.12065 0.2794)
			(end -0.12065 0.3048)
			(stroke
				(width 0.1)
				(type default)
			)
			(layer "F.Fab")
		)
		(fp_line
			(start -0.12065 -0.2794)
			(end 0.12065 -0.2794)
			(stroke
				(width 0.1)
				(type default)
			)
			(layer "F.Fab")
		)
		(fp_line
			(start -0.12065 -0.305054)
			(end -0.12065 -0.2794)
			(stroke
				(width 0.1)
				(type default)
			)
			(layer "F.Fab")
		)
		(fp_line
			(start -0.67945 0.3048)
			(end -0.67945 -0.305054)
			(stroke
				(width 0.1)
				(type default)
			)
			(layer "F.Fab")
		)
		(fp_line
			(start -0.67945 -0.305054)
			(end -0.12065 -0.305054)
			(stroke
				(width 0.1)
				(type default)
			)
			(layer "F.Fab")
		)
		(pad "1" smd circle
			(at -0.40005 0 180)
			(size 0 0)
			(layers "F.Cu" "F.Mask" "F.Paste")
			(net "P3V3_AUX")
		)
		(pad "2" smd circle
			(at 0.40005 0 180)
			(size 0 0)
			(layers "F.Cu" "F.Mask" "F.Paste")
			(net "GPU_3V3IO_RSVD3_FFU")
		)
	)
	(footprint ""
		(layer "F.Cu")
		(at 122.55627 -36.675568)
		(property "Reference" "C6025"
			(at 0 0 0)
			(layer "F.SilkS")
			(hide yes)
			(effects
				(font
					(size 1.27 1.27)
				)
			)
		)
		(property "Value" ""
			(at 0 0 0)
			(layer "F.Fab")
			(effects
				(font
					(size 1.27 1.27)
				)
			)
		)
		(duplicate_pad_numbers_are_jumpers no)
		(fp_line
			(start -0.7874 -0.4064)
			(end 0.7874 -0.4064)
			(stroke
				(width 0.1524)
				(type default)
			)
			(layer "F.SilkS")
		)
		(fp_line
			(start -0.7874 0.4064)
			(end -0.7874 -0.4064)
			(stroke
				(width 0.1524)
				(type default)
			)
			(layer "F.SilkS")
		)
		(fp_line
			(start 0.7874 -0.4064)
			(end 0.7874 0.4064)
			(stroke
				(width 0.1524)
				(type default)
			)
			(layer "F.SilkS")
		)
		(fp_line
			(start 0.7874 0.4064)
			(end -0.7874 0.4064)
			(stroke
				(width 0.1524)
				(type default)
			)
			(layer "F.SilkS")
		)
		(fp_line
			(start -0.6858 -0.3048)
			(end -0.1016 -0.3048)
			(stroke
				(width 0.1)
				(type default)
			)
			(layer "F.Fab")
		)
		(fp_line
			(start -0.6858 0.3048)
			(end -0.6858 -0.3048)
			(stroke
				(width 0.1)
				(type default)
			)
			(layer "F.Fab")
		)
		(fp_line
			(start -0.1016 -0.3048)
			(end -0.1016 -0.2794)
			(stroke
				(width 0.1)
				(type default)
			)
			(layer "F.Fab")
		)
		(fp_line
			(start -0.1016 -0.2794)
			(end 0.1016 -0.2794)
			(stroke
				(width 0.1)
				(type default)
			)
			(layer "F.Fab")
		)
		(fp_line
			(start -0.1016 0.2794)
			(end -0.1016 0.3048)
			(stroke
				(width 0.1)
				(type default)
			)
			(layer "F.Fab")
		)
		(fp_line
			(start -0.1016 0.3048)
			(end -0.6858 0.3048)
			(stroke
				(width 0.1)
				(type default)
			)
			(layer "F.Fab")
		)
		(fp_line
			(start 0.1016 -0.3048)
			(end 0.6858 -0.3048)
			(stroke
				(width 0.1)
				(type default)
			)
			(layer "F.Fab")
		)
		(fp_line
			(start 0.1016 -0.2794)
			(end 0.1016 -0.3048)
			(stroke
				(width 0.1)
				(type default)
			)
			(layer "F.Fab")
		)
		(fp_line
			(start 0.1016 0.2794)
			(end -0.1016 0.2794)
			(stroke
				(width 0.1)
				(type default)
			)
			(layer "F.Fab")
		)
		(fp_line
			(start 0.1016 0.3048)
			(end 0.1016 0.2794)
			(stroke
				(width 0.1)
				(type default)
			)
			(layer "F.Fab")
		)
		(fp_line
			(start 0.6858 -0.3048)
			(end 0.6858 0.3048)
			(stroke
				(width 0.1)
				(type default)
			)
			(layer "F.Fab")
		)
		(fp_line
			(start 0.6858 0.3048)
			(end 0.1016 0.3048)
			(stroke
				(width 0.1)
				(type default)
			)
			(layer "F.Fab")
		)
		(pad "1" smd rect
			(at -0.40005 0 180)
			(size 0.4572 0.508)
			(layers "F.Cu" "F.Mask" "F.Paste")
			(net "USB3_CPU0_BMC_HUB2_TX_DP")
		)
		(pad "2" smd rect
			(at 0.40005 0 180)
			(size 0.4572 0.508)
			(layers "F.Cu" "F.Mask" "F.Paste")
			(net "USB3_CPU0_BMC_TX_BUF_C_DP")
		)
	)
	(footprint ""
		(layer "F.Cu")
		(at 199.941942 -344.270584 180)
		(property "Reference" "PC120"
			(at 0 0 180)
			(layer "F.SilkS")
			(hide yes)
			(effects
				(font
					(size 1.27 1.27)
				)
			)
		)
		(property "Value" ""
			(at 0 0 180)
			(layer "F.Fab")
			(effects
				(font
					(size 1.27 1.27)
				)
			)
		)
		(duplicate_pad_numbers_are_jumpers no)
		(fp_line
			(start 1.524 0.762)
			(end -1.524 0.762)
			(stroke
				(width 0.1524)
				(type default)
			)
			(layer "F.SilkS")
		)
		(fp_line
			(start 1.524 -0.762)
			(end 1.524 0.762)
			(stroke
				(width 0.1524)
				(type default)
			)
			(layer "F.SilkS")
		)
		(fp_line
			(start -1.524 0.762)
			(end -1.524 -0.762)
			(stroke
				(width 0.1524)
				(type default)
			)
			(layer "F.SilkS")
		)
		(fp_line
			(start -1.524 -0.762)
			(end 1.524 -0.762)
			(stroke
				(width 0.1524)
				(type default)
			)
			(layer "F.SilkS")
		)
		(fp_line
			(start 1.1049 0.724916)
			(end 1.1049 -0.724916)
			(stroke
				(width 0.1)
				(type default)
			)
			(layer "F.Fab")
		)
		(fp_line
			(start 1.1049 -0.724916)
			(end -1.1049 -0.724916)
			(stroke
				(width 0.1)
				(type default)
			)
			(layer "F.Fab")
		)
		(fp_line
			(start -1.1049 0.724916)
			(end 1.1049 0.724916)
			(stroke
				(width 0.1)
				(type default)
			)
			(layer "F.Fab")
		)
		(fp_line
			(start -1.1049 -0.724916)
			(end -1.1049 0.724916)
			(stroke
				(width 0.1)
				(type default)
			)
			(layer "F.Fab")
		)
		(pad "1" smd rect
			(at -0.889 0)
			(size 1.016 1.27)
			(layers "F.Cu" "F.Mask" "F.Paste")
			(net "SW_P12V_AUX_PVDD_33_S5_FLT")
		)
		(pad "2" smd rect
			(at 0.889 0)
			(size 1.016 1.27)
			(layers "F.Cu" "F.Mask" "F.Paste")
			(net "GND")
		)
	)
)
